(kicad_pcb
	(version 20260206)
	(generator "pcbnew")
	(generator_version "10.0")
	(general
		(thickness 1.6)
		(legacy_teardrops no)
	)
	(paper "A4")
	(title_block
		(title "04192023_DAF0TMB3IC0_F0TG_MB_C_brd_V02_OCP.brd")
		(comment 1 "Grand Teton / footprints 6735-6742 of 8354")
	)
	(layers
		(0 "F.Cu" signal "TOP")
		(4 "In1.Cu" signal "GND")
		(6 "In2.Cu" signal "IN1")
		(8 "In3.Cu" signal "GND1")
		(10 "In4.Cu" signal "IN2")
		(12 "In5.Cu" signal "GND2")
		(14 "In6.Cu" signal "IN3")
		(16 "In7.Cu" signal "GND3")
		(18 "In8.Cu" signal "VCC")
		(20 "In9.Cu" signal "VCC1")
		(22 "In10.Cu" signal "GND4")
		(24 "In11.Cu" signal "IN4")
		(26 "In12.Cu" signal "GND5")
		(28 "In13.Cu" signal "IN5")
		(30 "In14.Cu" signal "GND6")
		(32 "In15.Cu" signal "IN6")
		(34 "In16.Cu" signal "GND7")
		(2 "B.Cu" signal "BOTTOM")
		(9 "F.Adhes" user "F.Adhesive")
		(11 "B.Adhes" user "B.Adhesive")
		(13 "F.Paste" user "Package Geometry/Pastemask Top")
		(15 "B.Paste" user "Package Geometry/Pastemask Bottom")
		(5 "F.SilkS" user "Ref Des/Silkscreen Top")
		(7 "B.SilkS" user "Ref Des/Silkscreen Bottom")
		(1 "F.Mask" user "Board Geometry/Soldermask Top")
		(3 "B.Mask" user "Board Geometry/Soldermask Bottom")
		(17 "Dwgs.User" user "User.Drawings")
		(19 "Cmts.User" user "User.Comments")
		(21 "Eco1.User" user "User.Eco1")
		(23 "Eco2.User" user "User.Eco2")
		(25 "Edge.Cuts" user "Board Geometry/Outline")
		(27 "Margin" user)
		(31 "F.CrtYd" user "Package Geometry/Place Bound Top")
		(29 "B.CrtYd" user "Package Geometry/Place Bound Bottom")
		(35 "F.Fab" user "Ref Des/Assembly Top")
		(33 "B.Fab" user "Ref Des/Assembly Bottom")
	)
	(footprint ""
		(layer "B.Cu")
		(at 347.897958 -245.868952 -90)
		(property "Reference" "C2183"
			(at 0 0 90)
			(layer "B.SilkS")
			(hide yes)
			(effects
				(font
					(size 1.27 1.27)
				)
				(justify mirror)
			)
		)
		(property "Value" ""
			(at 0 0 90)
			(layer "B.Fab")
			(effects
				(font
					(size 1.27 1.27)
				)
				(justify mirror)
			)
		)
		(duplicate_pad_numbers_are_jumpers no)
		(fp_line
			(start -0.7874 0.4064)
			(end 0.7874 0.4064)
			(stroke
				(width 0.1524)
				(type default)
			)
			(layer "B.SilkS")
		)
		(fp_line
			(start 0.7874 0.4064)
			(end 0.7874 -0.4064)
			(stroke
				(width 0.1524)
				(type default)
			)
			(layer "B.SilkS")
		)
		(fp_line
			(start -0.7874 -0.4064)
			(end -0.7874 0.4064)
			(stroke
				(width 0.1524)
				(type default)
			)
			(layer "B.SilkS")
		)
		(fp_line
			(start 0.7874 -0.4064)
			(end -0.7874 -0.4064)
			(stroke
				(width 0.1524)
				(type default)
			)
			(layer "B.SilkS")
		)
		(fp_line
			(start -0.67945 0.3048)
			(end -0.120396 0.3048)
			(stroke
				(width 0.1)
				(type default)
			)
			(layer "B.Fab")
		)
		(fp_line
			(start -0.120396 0.3048)
			(end -0.120396 0.2794)
			(stroke
				(width 0.1)
				(type default)
			)
			(layer "B.Fab")
		)
		(fp_line
			(start 0.12065 0.3048)
			(end 0.67945 0.3048)
			(stroke
				(width 0.1)
				(type default)
			)
			(layer "B.Fab")
		)
		(fp_line
			(start 0.67945 0.3048)
			(end 0.67945 -0.305054)
			(stroke
				(width 0.1)
				(type default)
			)
			(layer "B.Fab")
		)
		(fp_line
			(start -0.120396 0.2794)
			(end 0.12065 0.2794)
			(stroke
				(width 0.1)
				(type default)
			)
			(layer "B.Fab")
		)
		(fp_line
			(start 0.12065 0.2794)
			(end 0.12065 0.3048)
			(stroke
				(width 0.1)
				(type default)
			)
			(layer "B.Fab")
		)
		(fp_line
			(start -0.12065 -0.2794)
			(end -0.12065 -0.3048)
			(stroke
				(width 0.1)
				(type default)
			)
			(layer "B.Fab")
		)
		(fp_line
			(start 0.12065 -0.2794)
			(end -0.12065 -0.2794)
			(stroke
				(width 0.1)
				(type default)
			)
			(layer "B.Fab")
		)
		(fp_line
			(start -0.67945 -0.3048)
			(end -0.67945 0.3048)
			(stroke
				(width 0.1)
				(type default)
			)
			(layer "B.Fab")
		)
		(fp_line
			(start -0.12065 -0.3048)
			(end -0.67945 -0.3048)
			(stroke
				(width 0.1)
				(type default)
			)
			(layer "B.Fab")
		)
		(fp_line
			(start 0.12065 -0.305054)
			(end 0.12065 -0.2794)
			(stroke
				(width 0.1)
				(type default)
			)
			(layer "B.Fab")
		)
		(fp_line
			(start 0.67945 -0.305054)
			(end 0.12065 -0.305054)
			(stroke
				(width 0.1)
				(type default)
			)
			(layer "B.Fab")
		)
		(pad "1" smd circle
			(at 0.40005 0 90)
			(size 0 0)
			(layers "B.Cu" "B.Mask" "B.Paste")
			(net "PVDDCR_CPU0_P0")
		)
		(pad "2" smd circle
			(at -0.40005 0 90)
			(size 0 0)
			(layers "B.Cu" "B.Mask" "B.Paste")
			(net "GND")
		)
	)
	(footprint ""
		(layer "B.Cu")
		(at 190.668402 -19.311366 180)
		(property "Reference" "R1801"
			(at 0 0 0)
			(layer "B.SilkS")
			(hide yes)
			(effects
				(font
					(size 1.27 1.27)
				)
				(justify mirror)
			)
		)
		(property "Value" ""
			(at 0 0 0)
			(layer "B.Fab")
			(effects
				(font
					(size 1.27 1.27)
				)
				(justify mirror)
			)
		)
		(duplicate_pad_numbers_are_jumpers no)
		(fp_line
			(start 0.7874 0.4064)
			(end 0.7874 -0.4064)
			(stroke
				(width 0.1524)
				(type default)
			)
			(layer "B.SilkS")
		)
		(fp_line
			(start 0.7874 -0.4064)
			(end -0.7874 -0.4064)
			(stroke
				(width 0.1524)
				(type default)
			)
			(layer "B.SilkS")
		)
		(fp_line
			(start -0.7874 0.4064)
			(end 0.7874 0.4064)
			(stroke
				(width 0.1524)
				(type default)
			)
			(layer "B.SilkS")
		)
		(fp_line
			(start -0.7874 -0.4064)
			(end -0.7874 0.4064)
			(stroke
				(width 0.1524)
				(type default)
			)
			(layer "B.SilkS")
		)
		(fp_line
			(start 0.67945 0.3048)
			(end 0.67945 -0.305054)
			(stroke
				(width 0.1)
				(type default)
			)
			(layer "B.Fab")
		)
		(fp_line
			(start 0.67945 -0.305054)
			(end 0.12065 -0.305054)
			(stroke
				(width 0.1)
				(type default)
			)
			(layer "B.Fab")
		)
		(fp_line
			(start 0.12065 0.3048)
			(end 0.67945 0.3048)
			(stroke
				(width 0.1)
				(type default)
			)
			(layer "B.Fab")
		)
		(fp_line
			(start 0.12065 0.2794)
			(end 0.12065 0.3048)
			(stroke
				(width 0.1)
				(type default)
			)
			(layer "B.Fab")
		)
		(fp_line
			(start 0.12065 -0.2794)
			(end -0.12065 -0.2794)
			(stroke
				(width 0.1)
				(type default)
			)
			(layer "B.Fab")
		)
		(fp_line
			(start 0.12065 -0.305054)
			(end 0.12065 -0.2794)
			(stroke
				(width 0.1)
				(type default)
			)
			(layer "B.Fab")
		)
		(fp_line
			(start -0.120396 0.3048)
			(end -0.120396 0.2794)
			(stroke
				(width 0.1)
				(type default)
			)
			(layer "B.Fab")
		)
		(fp_line
			(start -0.120396 0.2794)
			(end 0.12065 0.2794)
			(stroke
				(width 0.1)
				(type default)
			)
			(layer "B.Fab")
		)
		(fp_line
			(start -0.12065 -0.2794)
			(end -0.12065 -0.3048)
			(stroke
				(width 0.1)
				(type default)
			)
			(layer "B.Fab")
		)
		(fp_line
			(start -0.12065 -0.3048)
			(end -0.67945 -0.3048)
			(stroke
				(width 0.1)
				(type default)
			)
			(layer "B.Fab")
		)
		(fp_line
			(start -0.67945 0.3048)
			(end -0.120396 0.3048)
			(stroke
				(width 0.1)
				(type default)
			)
			(layer "B.Fab")
		)
		(fp_line
			(start -0.67945 -0.3048)
			(end -0.67945 0.3048)
			(stroke
				(width 0.1)
				(type default)
			)
			(layer "B.Fab")
		)
		(pad "1" smd circle
			(at 0.40005 0)
			(size 0 0)
			(layers "B.Cu" "B.Mask" "B.Paste")
			(net "PRSNT0_N")
		)
		(pad "2" smd circle
			(at -0.40005 0)
			(size 0 0)
			(layers "B.Cu" "B.Mask" "B.Paste")
			(net "GND")
		)
	)
	(footprint ""
		(layer "B.Cu")
		(at 346.84589 -396.393162 -90)
		(property "Reference" "C601"
			(at 0 0 90)
			(layer "B.SilkS")
			(hide yes)
			(effects
				(font
					(size 1.27 1.27)
				)
				(justify mirror)
			)
		)
		(property "Value" ""
			(at 0 0 90)
			(layer "B.Fab")
			(effects
				(font
					(size 1.27 1.27)
				)
				(justify mirror)
			)
		)
		(duplicate_pad_numbers_are_jumpers no)
		(fp_line
			(start -0.299974 0.150114)
			(end 0.299974 0.150114)
			(stroke
				(width 0.1)
				(type default)
			)
			(layer "B.Fab")
		)
		(fp_line
			(start 0.299974 0.150114)
			(end 0.299974 -0.150114)
			(stroke
				(width 0.1)
				(type default)
			)
			(layer "B.Fab")
		)
		(fp_line
			(start -0.299974 -0.150114)
			(end -0.299974 0.150114)
			(stroke
				(width 0.1)
				(type default)
			)
			(layer "B.Fab")
		)
		(fp_line
			(start 0.299974 -0.150114)
			(end -0.299974 -0.150114)
			(stroke
				(width 0.1)
				(type default)
			)
			(layer "B.Fab")
		)
		(pad "1" smd rect
			(at 0.2667 0 90)
			(size 0.3048 0.381)
			(layers "B.Cu" "B.Mask" "B.Paste")
			(net "P1V8_CPU0_RT1_1A_1D")
		)
		(pad "2" smd rect
			(at -0.2667 0 90)
			(size 0.3048 0.381)
			(layers "B.Cu" "B.Mask" "B.Paste")
			(net "GND")
		)
	)
	(footprint ""
		(layer "B.Cu")
		(at 405.406352 -395.148562 90)
		(property "Reference" "C978"
			(at 0 0 90)
			(layer "B.SilkS")
			(hide yes)
			(effects
				(font
					(size 1.27 1.27)
				)
				(justify mirror)
			)
		)
		(property "Value" ""
			(at 0 0 90)
			(layer "B.Fab")
			(effects
				(font
					(size 1.27 1.27)
				)
				(justify mirror)
			)
		)
		(duplicate_pad_numbers_are_jumpers no)
		(fp_line
			(start 0.299974 -0.150114)
			(end -0.299974 -0.150114)
			(stroke
				(width 0.1)
				(type default)
			)
			(layer "B.Fab")
		)
		(fp_line
			(start -0.299974 -0.150114)
			(end -0.299974 0.150114)
			(stroke
				(width 0.1)
				(type default)
			)
			(layer "B.Fab")
		)
		(fp_line
			(start 0.299974 0.150114)
			(end 0.299974 -0.150114)
			(stroke
				(width 0.1)
				(type default)
			)
			(layer "B.Fab")
		)
		(fp_line
			(start -0.299974 0.150114)
			(end 0.299974 0.150114)
			(stroke
				(width 0.1)
				(type default)
			)
			(layer "B.Fab")
		)
		(pad "1" smd rect
			(at 0.2667 0 270)
			(size 0.3048 0.381)
			(layers "B.Cu" "B.Mask" "B.Paste")
			(net "P0V9_CPU0_RT2_2A")
		)
		(pad "2" smd rect
			(at -0.2667 0 270)
			(size 0.3048 0.381)
			(layers "B.Cu" "B.Mask" "B.Paste")
			(net "GND")
		)
	)
	(footprint ""
		(layer "B.Cu")
		(at 388.491222 -398.942052 90)
		(property "Reference" "C1036"
			(at 0 0 90)
			(layer "B.SilkS")
			(hide yes)
			(effects
				(font
					(size 1.27 1.27)
				)
				(justify mirror)
			)
		)
		(property "Value" ""
			(at 0 0 90)
			(layer "B.Fab")
			(effects
				(font
					(size 1.27 1.27)
				)
				(justify mirror)
			)
		)
		(duplicate_pad_numbers_are_jumpers no)
		(fp_line
			(start 0.7874 -0.4064)
			(end -0.7874 -0.4064)
			(stroke
				(width 0.1524)
				(type default)
			)
			(layer "B.SilkS")
		)
		(fp_line
			(start -0.7874 -0.4064)
			(end -0.7874 0.4064)
			(stroke
				(width 0.1524)
				(type default)
			)
			(layer "B.SilkS")
		)
		(fp_line
			(start 0.7874 0.4064)
			(end 0.7874 -0.4064)
			(stroke
				(width 0.1524)
				(type default)
			)
			(layer "B.SilkS")
		)
		(fp_line
			(start -0.7874 0.4064)
			(end 0.7874 0.4064)
			(stroke
				(width 0.1524)
				(type default)
			)
			(layer "B.SilkS")
		)
		(fp_line
			(start 0.67945 -0.305054)
			(end 0.12065 -0.305054)
			(stroke
				(width 0.1)
				(type default)
			)
			(layer "B.Fab")
		)
		(fp_line
			(start 0.12065 -0.305054)
			(end 0.12065 -0.2794)
			(stroke
				(width 0.1)
				(type default)
			)
			(layer "B.Fab")
		)
		(fp_line
			(start -0.12065 -0.3048)
			(end -0.67945 -0.3048)
			(stroke
				(width 0.1)
				(type default)
			)
			(layer "B.Fab")
		)
		(fp_line
			(start -0.67945 -0.3048)
			(end -0.67945 0.3048)
			(stroke
				(width 0.1)
				(type default)
			)
			(layer "B.Fab")
		)
		(fp_line
			(start 0.12065 -0.2794)
			(end -0.12065 -0.2794)
			(stroke
				(width 0.1)
				(type default)
			)
			(layer "B.Fab")
		)
		(fp_line
			(start -0.12065 -0.2794)
			(end -0.12065 -0.3048)
			(stroke
				(width 0.1)
				(type default)
			)
			(layer "B.Fab")
		)
		(fp_line
			(start 0.12065 0.2794)
			(end 0.12065 0.3048)
			(stroke
				(width 0.1)
				(type default)
			)
			(layer "B.Fab")
		)
		(fp_line
			(start -0.120396 0.2794)
			(end 0.12065 0.2794)
			(stroke
				(width 0.1)
				(type default)
			)
			(layer "B.Fab")
		)
		(fp_line
			(start 0.67945 0.3048)
			(end 0.67945 -0.305054)
			(stroke
				(width 0.1)
				(type default)
			)
			(layer "B.Fab")
		)
		(fp_line
			(start 0.12065 0.3048)
			(end 0.67945 0.3048)
			(stroke
				(width 0.1)
				(type default)
			)
			(layer "B.Fab")
		)
		(fp_line
			(start -0.120396 0.3048)
			(end -0.120396 0.2794)
			(stroke
				(width 0.1)
				(type default)
			)
			(layer "B.Fab")
		)
		(fp_line
			(start -0.67945 0.3048)
			(end -0.120396 0.3048)
			(stroke
				(width 0.1)
				(type default)
			)
			(layer "B.Fab")
		)
		(pad "1" smd circle
			(at 0.40005 0 270)
			(size 0 0)
			(layers "B.Cu" "B.Mask" "B.Paste")
			(net "P0V9_CPU0_RT3_2A")
		)
		(pad "2" smd circle
			(at -0.40005 0 270)
			(size 0 0)
			(layers "B.Cu" "B.Mask" "B.Paste")
			(net "GND")
		)
	)
	(footprint ""
		(layer "B.Cu")
		(at 293.12997 -350.65589 -90)
		(property "Reference" "PC157_2"
			(at 0 0 90)
			(layer "B.SilkS")
			(hide yes)
			(effects
				(font
					(size 1.27 1.27)
				)
				(justify mirror)
			)
		)
		(property "Value" ""
			(at 0 0 90)
			(layer "B.Fab")
			(effects
				(font
					(size 1.27 1.27)
				)
				(justify mirror)
			)
		)
		(duplicate_pad_numbers_are_jumpers no)
		(fp_line
			(start -1.524 0.762)
			(end 1.524 0.762)
			(stroke
				(width 0.1524)
				(type default)
			)
			(layer "B.SilkS")
		)
		(fp_line
			(start 1.524 0.762)
			(end 1.524 -0.762)
			(stroke
				(width 0.1524)
				(type default)
			)
			(layer "B.SilkS")
		)
		(fp_line
			(start -1.524 -0.762)
			(end -1.524 0.762)
			(stroke
				(width 0.1524)
				(type default)
			)
			(layer "B.SilkS")
		)
		(fp_line
			(start 1.524 -0.762)
			(end -1.524 -0.762)
			(stroke
				(width 0.1524)
				(type default)
			)
			(layer "B.SilkS")
		)
		(fp_line
			(start -1.1049 0.724916)
			(end -1.1049 -0.724916)
			(stroke
				(width 0.1)
				(type default)
			)
			(layer "B.Fab")
		)
		(fp_line
			(start 1.1049 0.724916)
			(end -1.1049 0.724916)
			(stroke
				(width 0.1)
				(type default)
			)
			(layer "B.Fab")
		)
		(fp_line
			(start -1.1049 -0.724916)
			(end 1.1049 -0.724916)
			(stroke
				(width 0.1)
				(type default)
			)
			(layer "B.Fab")
		)
		(fp_line
			(start 1.1049 -0.724916)
			(end 1.1049 0.724916)
			(stroke
				(width 0.1)
				(type default)
			)
			(layer "B.Fab")
		)
		(pad "1" smd rect
			(at 0.889 0 270)
			(size 1.016 1.27)
			(layers "B.Cu" "B.Mask" "B.Paste")
			(net "SW_P12V_AUX_PVDDIO_P0_FLT")
		)
		(pad "2" smd rect
			(at -0.889 0 270)
			(size 1.016 1.27)
			(layers "B.Cu" "B.Mask" "B.Paste")
			(net "GND")
		)
	)
	(footprint ""
		(layer "B.Cu")
		(at 460.405988 -44.416726)
		(property "Reference" "C5015"
			(at 0 0 0)
			(layer "B.SilkS")
			(hide yes)
			(effects
				(font
					(size 1.27 1.27)
				)
				(justify mirror)
			)
		)
		(property "Value" ""
			(at 0 0 0)
			(layer "B.Fab")
			(effects
				(font
					(size 1.27 1.27)
				)
				(justify mirror)
			)
		)
		(duplicate_pad_numbers_are_jumpers no)
		(fp_line
			(start -0.7874 -0.4064)
			(end -0.7874 0.4064)
			(stroke
				(width 0.1524)
				(type default)
			)
			(layer "B.SilkS")
		)
		(fp_line
			(start -0.7874 0.4064)
			(end 0.7874 0.4064)
			(stroke
				(width 0.1524)
				(type default)
			)
			(layer "B.SilkS")
		)
		(fp_line
			(start 0.7874 -0.4064)
			(end -0.7874 -0.4064)
			(stroke
				(width 0.1524)
				(type default)
			)
			(layer "B.SilkS")
		)
		(fp_line
			(start 0.7874 0.4064)
			(end 0.7874 -0.4064)
			(stroke
				(width 0.1524)
				(type default)
			)
			(layer "B.SilkS")
		)
		(fp_line
			(start -0.67945 -0.3048)
			(end -0.67945 0.3048)
			(stroke
				(width 0.1)
				(type default)
			)
			(layer "B.Fab")
		)
		(fp_line
			(start -0.67945 0.3048)
			(end -0.120396 0.3048)
			(stroke
				(width 0.1)
				(type default)
			)
			(layer "B.Fab")
		)
		(fp_line
			(start -0.12065 -0.3048)
			(end -0.67945 -0.3048)
			(stroke
				(width 0.1)
				(type default)
			)
			(layer "B.Fab")
		)
		(fp_line
			(start -0.12065 -0.2794)
			(end -0.12065 -0.3048)
			(stroke
				(width 0.1)
				(type default)
			)
			(layer "B.Fab")
		)
		(fp_line
			(start -0.120396 0.2794)
			(end 0.12065 0.2794)
			(stroke
				(width 0.1)
				(type default)
			)
			(layer "B.Fab")
		)
		(fp_line
			(start -0.120396 0.3048)
			(end -0.120396 0.2794)
			(stroke
				(width 0.1)
				(type default)
			)
			(layer "B.Fab")
		)
		(fp_line
			(start 0.12065 -0.305054)
			(end 0.12065 -0.2794)
			(stroke
				(width 0.1)
				(type default)
			)
			(layer "B.Fab")
		)
		(fp_line
			(start 0.12065 -0.2794)
			(end -0.12065 -0.2794)
			(stroke
				(width 0.1)
				(type default)
			)
			(layer "B.Fab")
		)
		(fp_line
			(start 0.12065 0.2794)
			(end 0.12065 0.3048)
			(stroke
				(width 0.1)
				(type default)
			)
			(layer "B.Fab")
		)
		(fp_line
			(start 0.12065 0.3048)
			(end 0.67945 0.3048)
			(stroke
				(width 0.1)
				(type default)
			)
			(layer "B.Fab")
		)
		(fp_line
			(start 0.67945 -0.305054)
			(end 0.12065 -0.305054)
			(stroke
				(width 0.1)
				(type default)
			)
			(layer "B.Fab")
		)
		(fp_line
			(start 0.67945 0.3048)
			(end 0.67945 -0.305054)
			(stroke
				(width 0.1)
				(type default)
			)
			(layer "B.Fab")
		)
		(pad "1" smd circle
			(at 0.40005 0 180)
			(size 0 0)
			(layers "B.Cu" "B.Mask" "B.Paste")
			(net "PWRGD_P3V3_AUX")
		)
		(pad "2" smd circle
			(at -0.40005 0 180)
			(size 0 0)
			(layers "B.Cu" "B.Mask" "B.Paste")
			(net "GND")
		)
	)
	(footprint ""
		(layer "B.Cu")
		(at 346.373958 -263.521952)
		(property "Reference" "C2604"
			(at 0 0 0)
			(layer "B.SilkS")
			(hide yes)
			(effects
				(font
					(size 1.27 1.27)
				)
				(justify mirror)
			)
		)
		(property "Value" ""
			(at 0 0 0)
			(layer "B.Fab")
			(effects
				(font
					(size 1.27 1.27)
				)
				(justify mirror)
			)
		)
		(duplicate_pad_numbers_are_jumpers no)
		(fp_line
			(start -0.7874 -0.4064)
			(end -0.7874 0.4064)
			(stroke
				(width 0.1524)
				(type default)
			)
			(layer "B.SilkS")
		)
		(fp_line
			(start -0.7874 0.4064)
			(end 0.7874 0.4064)
			(stroke
				(width 0.1524)
				(type default)
			)
			(layer "B.SilkS")
		)
		(fp_line
			(start 0.7874 -0.4064)
			(end -0.7874 -0.4064)
			(stroke
				(width 0.1524)
				(type default)
			)
			(layer "B.SilkS")
		)
		(fp_line
			(start 0.7874 0.4064)
			(end 0.7874 -0.4064)
			(stroke
				(width 0.1524)
				(type default)
			)
			(layer "B.SilkS")
		)
		(fp_line
			(start -0.67945 -0.3048)
			(end -0.67945 0.3048)
			(stroke
				(width 0.1)
				(type default)
			)
			(layer "B.Fab")
		)
		(fp_line
			(start -0.67945 0.3048)
			(end -0.120396 0.3048)
			(stroke
				(width 0.1)
				(type default)
			)
			(layer "B.Fab")
		)
		(fp_line
			(start -0.12065 -0.3048)
			(end -0.67945 -0.3048)
			(stroke
				(width 0.1)
				(type default)
			)
			(layer "B.Fab")
		)
		(fp_line
			(start -0.12065 -0.2794)
			(end -0.12065 -0.3048)
			(stroke
				(width 0.1)
				(type default)
			)
			(layer "B.Fab")
		)
		(fp_line
			(start -0.120396 0.2794)
			(end 0.12065 0.2794)
			(stroke
				(width 0.1)
				(type default)
			)
			(layer "B.Fab")
		)
		(fp_line
			(start -0.120396 0.3048)
			(end -0.120396 0.2794)
			(stroke
				(width 0.1)
				(type default)
			)
			(layer "B.Fab")
		)
		(fp_line
			(start 0.12065 -0.305054)
			(end 0.12065 -0.2794)
			(stroke
				(width 0.1)
				(type default)
			)
			(layer "B.Fab")
		)
		(fp_line
			(start 0.12065 -0.2794)
			(end -0.12065 -0.2794)
			(stroke
				(width 0.1)
				(type default)
			)
			(layer "B.Fab")
		)
		(fp_line
			(start 0.12065 0.2794)
			(end 0.12065 0.3048)
			(stroke
				(width 0.1)
				(type default)
			)
			(layer "B.Fab")
		)
		(fp_line
			(start 0.12065 0.3048)
			(end 0.67945 0.3048)
			(stroke
				(width 0.1)
				(type default)
			)
			(layer "B.Fab")
		)
		(fp_line
			(start 0.67945 -0.305054)
			(end 0.12065 -0.305054)
			(stroke
				(width 0.1)
				(type default)
			)
			(layer "B.Fab")
		)
		(fp_line
			(start 0.67945 0.3048)
			(end 0.67945 -0.305054)
			(stroke
				(width 0.1)
				(type default)
			)
			(layer "B.Fab")
		)
		(pad "1" smd circle
			(at 0.40005 0 180)
			(size 0 0)
			(layers "B.Cu" "B.Mask" "B.Paste")
			(net "PVDDIO_P0")
		)
		(pad "2" smd circle
			(at -0.40005 0 180)
			(size 0 0)
			(layers "B.Cu" "B.Mask" "B.Paste")
			(net "GND")
		)
	)
)
